(kicad_pcb
	(version 20260206)
	(generator "pcbnew")
	(generator_version "10.0")
	(general
		(thickness 1.6)
		(legacy_teardrops no)
	)
	(paper "A4")
	(title_block
		(title "Wiwynn_Tioga_Pass_MB.brd")
		(comment 1 "Tioga Pass / footprints 3945-3951 of 4770")
	)
	(layers
		(0 "F.Cu" signal "TOP")
		(4 "In1.Cu" signal "L2GND")
		(6 "In2.Cu" signal "L3")
		(8 "In3.Cu" signal "L4GND")
		(10 "In4.Cu" signal "L5")
		(12 "In5.Cu" signal "L6GND")
		(14 "In6.Cu" signal "L7VCC")
		(16 "In7.Cu" signal "L8VCC")
		(18 "In8.Cu" signal "L9GND")
		(20 "In9.Cu" signal "L10")
		(22 "In10.Cu" signal "L11GND")
		(24 "In11.Cu" signal "L12")
		(26 "In12.Cu" signal "L13GND")
		(2 "B.Cu" signal "BOTTOM")
		(9 "F.Adhes" user "F.Adhesive")
		(11 "B.Adhes" user "B.Adhesive")
		(13 "F.Paste" user "Package Geometry/Pastemask Top")
		(15 "B.Paste" user "Package Geometry/Pastemask Bottom")
		(5 "F.SilkS" user "Ref Des/Silkscreen Top")
		(7 "B.SilkS" user "Ref Des/Silkscreen Bottom")
		(1 "F.Mask" user "Board Geometry/Soldermask Top")
		(3 "B.Mask" user "Board Geometry/Soldermask Bottom")
		(17 "Dwgs.User" user "User.Drawings")
		(19 "Cmts.User" user "User.Comments")
		(21 "Eco1.User" user "User.Eco1")
		(23 "Eco2.User" user "User.Eco2")
		(25 "Edge.Cuts" user "Board Geometry/Outline")
		(27 "Margin" user)
		(31 "F.CrtYd" user "Package Geometry/Place Bound Top")
		(29 "B.CrtYd" user "Package Geometry/Place Bound Bottom")
		(35 "F.Fab" user "Ref Des/Assembly Top")
		(33 "B.Fab" user "Ref Des/Assembly Bottom")
	)
	(footprint ""
		(layer "B.Cu")
		(at 17.907 -47.371 -90)
		(property "Reference" "R9R5"
			(at 0 0 90)
			(layer "B.SilkS")
			(hide yes)
			(effects
				(font
					(size 1.27 1.27)
				)
				(justify mirror)
			)
		)
		(property "Value" ""
			(at 0 0 90)
			(layer "B.Fab")
			(effects
				(font
					(size 1.27 1.27)
				)
				(justify mirror)
			)
		)
		(duplicate_pad_numbers_are_jumpers no)
		(fp_poly
			(pts
				(xy 0.2794 -0.1016) (xy -0.2794 -0.1016) (xy -0.2794 0.9906) (xy 0.2794 0.9906)
			)
			(stroke
				(width 0)
				(type default)
			)
			(fill no)
			(layer "B.CrtYd")
		)
		(fp_line
			(start -0.2794 0.9906)
			(end -0.2794 -0.1016)
			(stroke
				(width 0.1)
				(type default)
			)
			(layer "B.Fab")
		)
		(fp_line
			(start 0.2794 0.9906)
			(end -0.2794 0.9906)
			(stroke
				(width 0.1)
				(type default)
			)
			(layer "B.Fab")
		)
		(fp_line
			(start -0.2794 -0.1016)
			(end 0.2794 -0.1016)
			(stroke
				(width 0.1)
				(type default)
			)
			(layer "B.Fab")
		)
		(fp_line
			(start 0.2794 -0.1016)
			(end 0.2794 0.9906)
			(stroke
				(width 0.1)
				(type default)
			)
			(layer "B.Fab")
		)
		(pad "1" smd rect
			(at 0 0 90)
			(size 0.508 0.508)
			(layers "B.Cu" "B.Mask" "B.Paste")
			(net "ISENSE_TMP421_2_E")
		)
		(pad "2" smd rect
			(at 0 0.889 90)
			(size 0.508 0.508)
			(layers "B.Cu" "B.Mask" "B.Paste")
			(net "ISENSE_TMP421_2_DXP")
		)
		(zone
			(layer "B.Cu")
			(hatch none 0.5)
			(connect_pads
				(clearance 0)
			)
			(min_thickness 0.25)
			(keepout
				(tracks not_allowed)
				(vias allowed)
				(pads allowed)
				(copperpour not_allowed)
				(footprints allowed)
			)
			(placement
				(enabled no)
				(sheetname "")
			)
			(fill
				(thermal_gap 0.5)
				(thermal_bridge_width 0.5)
				(island_removal_mode 0)
			)
			(polygon
				(pts
					(xy 17.272 -47.117) (xy 17.272 -47.625) (xy 17.653 -47.625) (xy 17.653 -47.117)
				)
			)
		)
		(zone
			(layer "B.Cu")
			(hatch none 0.5)
			(connect_pads
				(clearance 0)
			)
			(min_thickness 0.25)
			(keepout
				(tracks allowed)
				(vias not_allowed)
				(pads allowed)
				(copperpour not_allowed)
				(footprints allowed)
			)
			(placement
				(enabled no)
				(sheetname "")
			)
			(fill
				(thermal_gap 0.5)
				(thermal_bridge_width 0.5)
				(island_removal_mode 0)
			)
			(polygon
				(pts
					(xy 17.653 -47.117) (xy 17.653 -47.625) (xy 17.272 -47.625) (xy 17.272 -47.117)
				)
			)
		)
	)
	(footprint ""
		(layer "B.Cu")
		(at 157.08122 -121.4247 180)
		(property "Reference" "R7M7"
			(at 0 0 0)
			(layer "B.SilkS")
			(hide yes)
			(effects
				(font
					(size 1.27 1.27)
				)
				(justify mirror)
			)
		)
		(property "Value" ""
			(at 0 0 0)
			(layer "B.Fab")
			(effects
				(font
					(size 1.27 1.27)
				)
				(justify mirror)
			)
		)
		(duplicate_pad_numbers_are_jumpers no)
		(fp_poly
			(pts
				(xy 0.2794 -0.1016) (xy -0.2794 -0.1016) (xy -0.2794 0.9906) (xy 0.2794 0.9906)
			)
			(stroke
				(width 0)
				(type default)
			)
			(fill no)
			(layer "B.CrtYd")
		)
		(fp_line
			(start 0.2794 0.9906)
			(end -0.2794 0.9906)
			(stroke
				(width 0.1)
				(type default)
			)
			(layer "B.Fab")
		)
		(fp_line
			(start 0.2794 -0.1016)
			(end 0.2794 0.9906)
			(stroke
				(width 0.1)
				(type default)
			)
			(layer "B.Fab")
		)
		(fp_line
			(start -0.2794 0.9906)
			(end -0.2794 -0.1016)
			(stroke
				(width 0.1)
				(type default)
			)
			(layer "B.Fab")
		)
		(fp_line
			(start -0.2794 -0.1016)
			(end 0.2794 -0.1016)
			(stroke
				(width 0.1)
				(type default)
			)
			(layer "B.Fab")
		)
		(pad "1" smd rect
			(at 0 0)
			(size 0.508 0.508)
			(layers "B.Cu" "B.Mask" "B.Paste")
			(net "PVCCIO_CPU1")
		)
		(pad "2" smd rect
			(at 0 0.889)
			(size 0.508 0.508)
			(layers "B.Cu" "B.Mask" "B.Paste")
			(net "SMB_DDR_KLM_SDA_G")
		)
		(zone
			(layer "B.Cu")
			(hatch none 0.5)
			(connect_pads
				(clearance 0)
			)
			(min_thickness 0.25)
			(keepout
				(tracks not_allowed)
				(vias allowed)
				(pads allowed)
				(copperpour not_allowed)
				(footprints allowed)
			)
			(placement
				(enabled no)
				(sheetname "")
			)
			(fill
				(thermal_gap 0.5)
				(thermal_bridge_width 0.5)
				(island_removal_mode 0)
			)
			(polygon
				(pts
					(xy 156.82722 -122.0597) (xy 157.33522 -122.0597) (xy 157.33522 -121.6787) (xy 156.82722 -121.6787)
				)
			)
		)
		(zone
			(layer "B.Cu")
			(hatch none 0.5)
			(connect_pads
				(clearance 0)
			)
			(min_thickness 0.25)
			(keepout
				(tracks allowed)
				(vias not_allowed)
				(pads allowed)
				(copperpour not_allowed)
				(footprints allowed)
			)
			(placement
				(enabled no)
				(sheetname "")
			)
			(fill
				(thermal_gap 0.5)
				(thermal_bridge_width 0.5)
				(island_removal_mode 0)
			)
			(polygon
				(pts
					(xy 156.82722 -121.6787) (xy 157.33522 -121.6787) (xy 157.33522 -122.0597) (xy 156.82722 -122.0597)
				)
			)
		)
	)
	(footprint ""
		(layer "B.Cu")
		(at 476.414084 -135.41756 -90)
		(property "Reference" "R1W37"
			(at 0.8382 -0.67818 270)
			(unlocked yes)
			(layer "B.SilkS")
			(effects
				(font
					(size 0.4064 0.254)
					(thickness 0.1524)
				)
				(justify left mirror)
			)
		)
		(property "Value" ""
			(at 0 0 90)
			(layer "B.Fab")
			(effects
				(font
					(size 1.27 1.27)
				)
				(justify mirror)
			)
		)
		(duplicate_pad_numbers_are_jumpers no)
		(fp_poly
			(pts
				(xy 0.2794 -0.1016) (xy -0.2794 -0.1016) (xy -0.2794 0.9906) (xy 0.2794 0.9906)
			)
			(stroke
				(width 0)
				(type default)
			)
			(fill no)
			(layer "B.CrtYd")
		)
		(fp_line
			(start -0.2794 0.9906)
			(end -0.2794 -0.1016)
			(stroke
				(width 0.1)
				(type default)
			)
			(layer "B.Fab")
		)
		(fp_line
			(start 0.2794 0.9906)
			(end -0.2794 0.9906)
			(stroke
				(width 0.1)
				(type default)
			)
			(layer "B.Fab")
		)
		(fp_line
			(start -0.2794 -0.1016)
			(end 0.2794 -0.1016)
			(stroke
				(width 0.1)
				(type default)
			)
			(layer "B.Fab")
		)
		(fp_line
			(start 0.2794 -0.1016)
			(end 0.2794 0.9906)
			(stroke
				(width 0.1)
				(type default)
			)
			(layer "B.Fab")
		)
		(pad "1" smd rect
			(at 0 0 90)
			(size 0.508 0.508)
			(layers "B.Cu" "B.Mask" "B.Paste")
			(net "P3V3_STBY")
		)
		(pad "2" smd rect
			(at 0 0.889 90)
			(size 0.508 0.508)
			(layers "B.Cu" "B.Mask" "B.Paste")
			(net "SMB_DEBUG_STBY_LVC3_SDA_CONN")
		)
		(zone
			(layer "B.Cu")
			(hatch none 0.5)
			(connect_pads
				(clearance 0)
			)
			(min_thickness 0.25)
			(keepout
				(tracks not_allowed)
				(vias allowed)
				(pads allowed)
				(copperpour not_allowed)
				(footprints allowed)
			)
			(placement
				(enabled no)
				(sheetname "")
			)
			(fill
				(thermal_gap 0.5)
				(thermal_bridge_width 0.5)
				(island_removal_mode 0)
			)
			(polygon
				(pts
					(xy 475.779084 -135.16356) (xy 475.779084 -135.67156) (xy 476.160084 -135.67156) (xy 476.160084 -135.16356)
				)
			)
		)
		(zone
			(layer "B.Cu")
			(hatch none 0.5)
			(connect_pads
				(clearance 0)
			)
			(min_thickness 0.25)
			(keepout
				(tracks allowed)
				(vias not_allowed)
				(pads allowed)
				(copperpour not_allowed)
				(footprints allowed)
			)
			(placement
				(enabled no)
				(sheetname "")
			)
			(fill
				(thermal_gap 0.5)
				(thermal_bridge_width 0.5)
				(island_removal_mode 0)
			)
			(polygon
				(pts
					(xy 476.160084 -135.16356) (xy 476.160084 -135.67156) (xy 475.779084 -135.67156) (xy 475.779084 -135.16356)
				)
			)
		)
	)
	(footprint ""
		(layer "B.Cu")
		(at 414.2105 -4.318 -90)
		(property "Reference" "R2P20"
			(at 0 0 90)
			(layer "B.SilkS")
			(hide yes)
			(effects
				(font
					(size 1.27 1.27)
				)
				(justify mirror)
			)
		)
		(property "Value" ""
			(at 0 0 90)
			(layer "B.Fab")
			(effects
				(font
					(size 1.27 1.27)
				)
				(justify mirror)
			)
		)
		(duplicate_pad_numbers_are_jumpers no)
		(fp_rect
			(start 0.2794 -0.1016)
			(end -0.2794 0.9906)
			(stroke
				(width 0)
				(type default)
			)
			(fill no)
			(layer "B.CrtYd")
		)
		(fp_line
			(start -0.2794 0.9906)
			(end -0.2794 -0.1016)
			(stroke
				(width 0.1)
				(type default)
			)
			(layer "B.Fab")
		)
		(fp_line
			(start 0.2794 0.9906)
			(end -0.2794 0.9906)
			(stroke
				(width 0.1)
				(type default)
			)
			(layer "B.Fab")
		)
		(fp_line
			(start -0.2794 -0.1016)
			(end 0.2794 -0.1016)
			(stroke
				(width 0.1)
				(type default)
			)
			(layer "B.Fab")
		)
		(fp_line
			(start 0.2794 -0.1016)
			(end 0.2794 0.9906)
			(stroke
				(width 0.1)
				(type default)
			)
			(layer "B.Fab")
		)
		(pad "1" smd rect
			(at 0 0 90)
			(size 0.508 0.508)
			(layers "B.Cu" "B.Mask" "B.Paste")
			(net "PWRGD_P5V_R")
		)
		(pad "2" smd rect
			(at 0 0.889 90)
			(size 0.508 0.508)
			(layers "B.Cu" "B.Mask" "B.Paste")
			(net "PWRGD_P5V")
		)
		(zone
			(layer "B.Cu")
			(hatch none 0.5)
			(connect_pads
				(clearance 0)
			)
			(min_thickness 0.25)
			(keepout
				(tracks allowed)
				(vias not_allowed)
				(pads allowed)
				(copperpour not_allowed)
				(footprints allowed)
			)
			(placement
				(enabled no)
				(sheetname "")
			)
			(fill
				(thermal_gap 0.5)
				(thermal_bridge_width 0.5)
				(island_removal_mode 0)
			)
			(polygon
				(pts
					(xy 413.9565 -4.064) (xy 413.9565 -4.572) (xy 413.5755 -4.572) (xy 413.5755 -4.064)
				)
			)
		)
		(zone
			(layer "B.Cu")
			(hatch none 0.5)
			(connect_pads
				(clearance 0)
			)
			(min_thickness 0.25)
			(keepout
				(tracks not_allowed)
				(vias allowed)
				(pads allowed)
				(copperpour not_allowed)
				(footprints allowed)
			)
			(placement
				(enabled no)
				(sheetname "")
			)
			(fill
				(thermal_gap 0.5)
				(thermal_bridge_width 0.5)
				(island_removal_mode 0)
			)
			(polygon
				(pts
					(xy 413.9565 -4.064) (xy 413.9565 -4.572) (xy 413.5755 -4.572) (xy 413.5755 -4.064)
				)
			)
		)
	)
	(footprint ""
		(layer "B.Cu")
		(at 348.57436 -77.788516 180)
		(property "Reference" "C3P25"
			(at 0 0 0)
			(layer "B.SilkS")
			(hide yes)
			(effects
				(font
					(size 1.27 1.27)
				)
				(justify mirror)
			)
		)
		(property "Value" ""
			(at 0 0 0)
			(layer "B.Fab")
			(effects
				(font
					(size 1.27 1.27)
				)
				(justify mirror)
			)
		)
		(duplicate_pad_numbers_are_jumpers no)
		(fp_poly
			(pts
				(xy -0.3048 -0.1016) (xy -0.3048 0.9906) (xy 0.3048 0.9906) (xy 0.3048 -0.1016)
			)
			(stroke
				(width 0)
				(type default)
			)
			(fill no)
			(layer "B.CrtYd")
		)
		(fp_line
			(start 0.3048 0.9906)
			(end -0.3048 0.9906)
			(stroke
				(width 0.1)
				(type default)
			)
			(layer "B.Fab")
		)
		(fp_line
			(start 0.3048 -0.1016)
			(end 0.3048 0.9906)
			(stroke
				(width 0.1)
				(type default)
			)
			(layer "B.Fab")
		)
		(fp_line
			(start -0.3048 0.9906)
			(end -0.3048 -0.1016)
			(stroke
				(width 0.1)
				(type default)
			)
			(layer "B.Fab")
		)
		(fp_line
			(start -0.3048 -0.1016)
			(end 0.3048 -0.1016)
			(stroke
				(width 0.1)
				(type default)
			)
			(layer "B.Fab")
		)
		(pad "1" smd rect
			(at 0 0)
			(size 0.508 0.508)
			(layers "B.Cu" "B.Mask" "B.Paste")
			(net "P3E_CPU0_PE1_SS_TXN<3>")
		)
		(pad "2" smd rect
			(at 0 0.889)
			(size 0.508 0.508)
			(layers "B.Cu" "B.Mask" "B.Paste")
			(net "P3E_CPU0_PE1_PCH_TXN<3>")
		)
		(zone
			(layer "B.Cu")
			(hatch none 0.5)
			(connect_pads
				(clearance 0)
			)
			(min_thickness 0.25)
			(keepout
				(tracks not_allowed)
				(vias allowed)
				(pads allowed)
				(copperpour not_allowed)
				(footprints allowed)
			)
			(placement
				(enabled no)
				(sheetname "")
			)
			(fill
				(thermal_gap 0.5)
				(thermal_bridge_width 0.5)
				(island_removal_mode 0)
			)
			(polygon
				(pts
					(xy 348.32036 -78.423516) (xy 348.82836 -78.423516) (xy 348.82836 -78.042516) (xy 348.32036 -78.042516)
				)
			)
		)
		(zone
			(layer "B.Cu")
			(hatch none 0.5)
			(connect_pads
				(clearance 0)
			)
			(min_thickness 0.25)
			(keepout
				(tracks allowed)
				(vias not_allowed)
				(pads allowed)
				(copperpour not_allowed)
				(footprints allowed)
			)
			(placement
				(enabled no)
				(sheetname "")
			)
			(fill
				(thermal_gap 0.5)
				(thermal_bridge_width 0.5)
				(island_removal_mode 0)
			)
			(polygon
				(pts
					(xy 348.32036 -78.042516) (xy 348.82836 -78.042516) (xy 348.82836 -78.423516) (xy 348.32036 -78.423516)
				)
			)
		)
	)
	(footprint ""
		(layer "B.Cu")
		(at 371.8306 -51.3207 180)
		(property "Reference" "R3P32"
			(at 0 0 0)
			(layer "B.SilkS")
			(hide yes)
			(effects
				(font
					(size 1.27 1.27)
				)
				(justify mirror)
			)
		)
		(property "Value" ""
			(at 0 0 0)
			(layer "B.Fab")
			(effects
				(font
					(size 1.27 1.27)
				)
				(justify mirror)
			)
		)
		(duplicate_pad_numbers_are_jumpers no)
		(fp_poly
			(pts
				(xy 0.2794 -0.1016) (xy -0.2794 -0.1016) (xy -0.2794 0.9906) (xy 0.2794 0.9906)
			)
			(stroke
				(width 0)
				(type default)
			)
			(fill no)
			(layer "B.CrtYd")
		)
		(fp_line
			(start 0.2794 0.9906)
			(end -0.2794 0.9906)
			(stroke
				(width 0.1)
				(type default)
			)
			(layer "B.Fab")
		)
		(fp_line
			(start 0.2794 -0.1016)
			(end 0.2794 0.9906)
			(stroke
				(width 0.1)
				(type default)
			)
			(layer "B.Fab")
		)
		(fp_line
			(start -0.2794 0.9906)
			(end -0.2794 -0.1016)
			(stroke
				(width 0.1)
				(type default)
			)
			(layer "B.Fab")
		)
		(fp_line
			(start -0.2794 -0.1016)
			(end 0.2794 -0.1016)
			(stroke
				(width 0.1)
				(type default)
			)
			(layer "B.Fab")
		)
		(pad "1" smd rect
			(at 0 0)
			(size 0.508 0.508)
			(layers "B.Cu" "B.Mask" "B.Paste")
			(net "GND")
		)
		(pad "2" smd rect
			(at 0 0.889)
			(size 0.508 0.508)
			(layers "B.Cu" "B.Mask" "B.Paste")
			(net "PD_GTL2014_1_VREF")
		)
		(zone
			(layer "B.Cu")
			(hatch none 0.5)
			(connect_pads
				(clearance 0)
			)
			(min_thickness 0.25)
			(keepout
				(tracks not_allowed)
				(vias allowed)
				(pads allowed)
				(copperpour not_allowed)
				(footprints allowed)
			)
			(placement
				(enabled no)
				(sheetname "")
			)
			(fill
				(thermal_gap 0.5)
				(thermal_bridge_width 0.5)
				(island_removal_mode 0)
			)
			(polygon
				(pts
					(xy 371.5766 -51.9557) (xy 372.0846 -51.9557) (xy 372.0846 -51.5747) (xy 371.5766 -51.5747)
				)
			)
		)
		(zone
			(layer "B.Cu")
			(hatch none 0.5)
			(connect_pads
				(clearance 0)
			)
			(min_thickness 0.25)
			(keepout
				(tracks allowed)
				(vias not_allowed)
				(pads allowed)
				(copperpour not_allowed)
				(footprints allowed)
			)
			(placement
				(enabled no)
				(sheetname "")
			)
			(fill
				(thermal_gap 0.5)
				(thermal_bridge_width 0.5)
				(island_removal_mode 0)
			)
			(polygon
				(pts
					(xy 371.5766 -51.5747) (xy 372.0846 -51.5747) (xy 372.0846 -51.9557) (xy 371.5766 -51.9557)
				)
			)
		)
	)
	(footprint ""
		(layer "B.Cu")
		(at 166.497 -74.549)
		(property "Reference" "R6P23"
			(at 0 0 0)
			(layer "B.SilkS")
			(hide yes)
			(effects
				(font
					(size 1.27 1.27)
				)
				(justify mirror)
			)
		)
		(property "Value" ""
			(at 0 0 0)
			(layer "B.Fab")
			(effects
				(font
					(size 1.27 1.27)
				)
				(justify mirror)
			)
		)
		(duplicate_pad_numbers_are_jumpers no)
		(fp_poly
			(pts
				(xy 0.2794 -0.1016) (xy -0.2794 -0.1016) (xy -0.2794 0.9906) (xy 0.2794 0.9906)
			)
			(stroke
				(width 0)
				(type default)
			)
			(fill no)
			(layer "B.CrtYd")
		)
		(fp_line
			(start -0.2794 -0.1016)
			(end 0.2794 -0.1016)
			(stroke
				(width 0.1)
				(type default)
			)
			(layer "B.Fab")
		)
		(fp_line
			(start -0.2794 0.9906)
			(end -0.2794 -0.1016)
			(stroke
				(width 0.1)
				(type default)
			)
			(layer "B.Fab")
		)
		(fp_line
			(start 0.2794 -0.1016)
			(end 0.2794 0.9906)
			(stroke
				(width 0.1)
				(type default)
			)
			(layer "B.Fab")
		)
		(fp_line
			(start 0.2794 0.9906)
			(end -0.2794 0.9906)
			(stroke
				(width 0.1)
				(type default)
			)
			(layer "B.Fab")
		)
		(pad "1" smd rect
			(at 0 0 180)
			(size 0.508 0.508)
			(layers "B.Cu" "B.Mask" "B.Paste")
			(net "FM_100M_N")
		)
		(pad "2" smd rect
			(at 0 0.889 180)
			(size 0.508 0.508)
			(layers "B.Cu" "B.Mask" "B.Paste")
			(net "GND")
		)
		(zone
			(layer "B.Cu")
			(hatch none 0.5)
			(connect_pads
				(clearance 0)
			)
			(min_thickness 0.25)
			(keepout
				(tracks allowed)
				(vias not_allowed)
				(pads allowed)
				(copperpour not_allowed)
				(footprints allowed)
			)
			(placement
				(enabled no)
				(sheetname "")
			)
			(fill
				(thermal_gap 0.5)
				(thermal_bridge_width 0.5)
				(island_removal_mode 0)
			)
			(polygon
				(pts
					(xy 166.751 -74.295) (xy 166.243 -74.295) (xy 166.243 -73.914) (xy 166.751 -73.914)
				)
			)
		)
		(zone
			(layer "B.Cu")
			(hatch none 0.5)
			(connect_pads
				(clearance 0)
			)
			(min_thickness 0.25)
			(keepout
				(tracks not_allowed)
				(vias allowed)
				(pads allowed)
				(copperpour not_allowed)
				(footprints allowed)
			)
			(placement
				(enabled no)
				(sheetname "")
			)
			(fill
				(thermal_gap 0.5)
				(thermal_bridge_width 0.5)
				(island_removal_mode 0)
			)
			(polygon
				(pts
					(xy 166.751 -73.914) (xy 166.243 -73.914) (xy 166.243 -74.295) (xy 166.751 -74.295)
				)
			)
		)
	)
)
